(kicad_pcb
	(version 20241229)
	(generator "pcbnew")
	(generator_version "9.0")
	(general
		(thickness 1.59)
		(legacy_teardrops no)
	)
	(paper "A3")
	(title_block
		(title "usb-c-power-adapter")
		(date "2025-06-24")
		(rev "1.1.2")
		(company "Antmicro")
		(comment 9 "footprints 27-32 of 122")
	)
	(layers
		(0 "F.Cu" signal)
		(4 "In1.Cu" signal)
		(6 "In2.Cu" signal)
		(2 "B.Cu" signal)
		(9 "F.Adhes" user "F.Adhesive")
		(11 "B.Adhes" user "B.Adhesive")
		(13 "F.Paste" user)
		(15 "B.Paste" user)
		(5 "F.SilkS" user "F.Silkscreen")
		(7 "B.SilkS" user "B.Silkscreen")
		(1 "F.Mask" user)
		(3 "B.Mask" user)
		(17 "Dwgs.User" user "User.Drawings")
		(19 "Cmts.User" user "User.Comments")
		(21 "Eco1.User" user "User.Eco1")
		(23 "Eco2.User" user "User.Eco2")
		(25 "Edge.Cuts" user)
		(27 "Margin" user)
		(31 "F.CrtYd" user "F.Courtyard")
		(29 "B.CrtYd" user "B.Courtyard")
		(35 "F.Fab" user)
		(33 "B.Fab" user)
	)
	(footprint "antmicro-footprints:R_0402_1005Metric"
		(layer "F.Cu")
		(at 102.576 72.35 90)
		(descr "Resistor SMD 0402")
		(tags "resistor SMD 0402")
		(property "Reference" "R30"
			(at -5.862 -4.102 0)
			(layer "B.SilkS")
			(effects
				(font
					(size 0.7 0.7)
					(thickness 0.15)
				)
				(justify left bottom mirror)
			)
		)
		(property "Value" "R_220R_0402"
			(at -1.011843 1.772047 90)
			(layer "F.Fab")
			(effects
				(font
					(size 0.7 0.7)
					(thickness 0.15)
				)
				(justify left bottom)
			)
		)
		(property "Datasheet" "https://www.bourns.com/docs/product-datasheets/cr.pdf"
			(at 0 0 90)
			(layer "F.Fab")
			(hide yes)
			(effects
				(font
					(size 1.27 1.27)
					(thickness 0.15)
				)
			)
		)
		(property "Description" "SMD Chip Resistor, 220 ohm, ± 1%, 62.5 mW, 0402 [1005 Metric], Thick Film, General Purpose"
			(at 0 0 90)
			(layer "F.Fab")
			(hide yes)
			(effects
				(font
					(size 1.27 1.27)
					(thickness 0.15)
				)
			)
		)
		(property "MPN" "CR0402-FX-2200GLF"
			(at 0 0 90)
			(unlocked yes)
			(layer "F.Fab")
			(hide yes)
			(effects
				(font
					(size 1 1)
					(thickness 0.15)
				)
			)
		)
		(property "Manufacturer" "Bourns"
			(at 0 0 90)
			(unlocked yes)
			(layer "F.Fab")
			(hide yes)
			(effects
				(font
					(size 1 1)
					(thickness 0.15)
				)
			)
		)
		(property "License" "Apache-2.0"
			(at 0 0 90)
			(unlocked yes)
			(layer "F.Fab")
			(hide yes)
			(effects
				(font
					(size 1 1)
					(thickness 0.15)
				)
			)
		)
		(property "Author" "Antmicro"
			(at 0 0 90)
			(unlocked yes)
			(layer "F.Fab")
			(hide yes)
			(effects
				(font
					(size 1 1)
					(thickness 0.15)
				)
			)
		)
		(property "Val" "220R"
			(at 0 0 90)
			(unlocked yes)
			(layer "F.Fab")
			(hide yes)
			(effects
				(font
					(size 1 1)
					(thickness 0.15)
				)
			)
		)
		(property "Tolerance" "1%"
			(at 0 0 90)
			(unlocked yes)
			(layer "F.Fab")
			(hide yes)
			(effects
				(font
					(size 1 1)
					(thickness 0.15)
				)
			)
		)
		(sheetname "/DC-DC Converters/")
		(sheetfile "dc-dc_converters.kicad_sch")
		(attr smd)
		(fp_rect
			(start -0.925 -0.47)
			(end 0.925 0.47)
			(stroke
				(width 0.05)
				(type default)
			)
			(fill no)
			(layer "F.CrtYd")
		)
		(fp_rect
			(start -0.5 -0.25)
			(end 0.5 0.25)
			(stroke
				(width 0.15)
				(type solid)
			)
			(fill no)
			(layer "F.Fab")
		)
		(pad "1" smd roundrect
			(at -0.48 0 90)
			(size 0.59 0.64)
			(layers "F.Cu" "F.Mask" "F.Paste")
			(roundrect_rratio 0.25)
			(net 69 "Net-(D9-A)")
			(pintype "passive")
		)
		(pad "2" smd roundrect
			(at 0.48 0 90)
			(size 0.59 0.64)
			(layers "F.Cu" "F.Mask" "F.Paste")
			(roundrect_rratio 0.25)
			(net 1 "+3V3")
			(pintype "passive")
		)
	)
	(footprint "antmicro-footprints:R_0402_1005Metric"
		(layer "F.Cu")
		(at 100 80.577)
		(descr "Resistor SMD 0402")
		(tags "resistor SMD 0402")
		(property "Reference" "R6"
			(at 1.092 0.449 0)
			(layer "F.SilkS")
			(effects
				(font
					(size 0.7 0.7)
					(thickness 0.15)
				)
				(justify left bottom)
			)
		)
		(property "Value" "R_0R_0402"
			(at -1.011843 1.772047 0)
			(layer "F.Fab")
			(effects
				(font
					(size 0.7 0.7)
					(thickness 0.15)
				)
				(justify left bottom)
			)
		)
		(property "Datasheet" "https://industrial.panasonic.com/cdbs/www-data/pdf/RDA0000/AOA0000C301.pdf"
			(at 0 0 0)
			(layer "F.Fab")
			(hide yes)
			(effects
				(font
					(size 1.27 1.27)
					(thickness 0.15)
				)
			)
		)
		(property "Description" "SMD Chip Resistor, Jumper, 0 ohm, 100 mW, 0402 [1005 Metric], Thick Film, General Purpose"
			(at 0 0 0)
			(layer "F.Fab")
			(hide yes)
			(effects
				(font
					(size 1.27 1.27)
					(thickness 0.15)
				)
			)
		)
		(property "Manufacturer" "Panasonic"
			(at 0 0 0)
			(unlocked yes)
			(layer "F.Fab")
			(hide yes)
			(effects
				(font
					(size 1 1)
					(thickness 0.15)
				)
			)
		)
		(property "MPN" "ERJ2GE0R00X"
			(at 0 0 0)
			(unlocked yes)
			(layer "F.Fab")
			(hide yes)
			(effects
				(font
					(size 1 1)
					(thickness 0.15)
				)
			)
		)
		(property "Val" "0R"
			(at 0 0 0)
			(unlocked yes)
			(layer "F.Fab")
			(hide yes)
			(effects
				(font
					(size 1 1)
					(thickness 0.15)
				)
			)
		)
		(property "License" "Apache-2.0"
			(at 0 0 0)
			(unlocked yes)
			(layer "F.Fab")
			(hide yes)
			(effects
				(font
					(size 1 1)
					(thickness 0.15)
				)
			)
		)
		(property "Author" "Antmicro"
			(at 0 0 0)
			(unlocked yes)
			(layer "F.Fab")
			(hide yes)
			(effects
				(font
					(size 1 1)
					(thickness 0.15)
				)
			)
		)
		(property "Tolerance" ""
			(at 0 0 0)
			(unlocked yes)
			(layer "F.Fab")
			(hide yes)
			(effects
				(font
					(size 1 1)
					(thickness 0.15)
				)
			)
		)
		(property "Current" "1A"
			(at 0 0 0)
			(unlocked yes)
			(layer "F.Fab")
			(hide yes)
			(effects
				(font
					(size 1 1)
					(thickness 0.15)
				)
			)
		)
		(sheetname "/DC-DC Converters/")
		(sheetfile "dc-dc_converters.kicad_sch")
		(attr smd)
		(fp_rect
			(start -0.925 -0.47)
			(end 0.925 0.47)
			(stroke
				(width 0.05)
				(type default)
			)
			(fill no)
			(layer "F.CrtYd")
		)
		(fp_rect
			(start -0.5 -0.25)
			(end 0.5 0.25)
			(stroke
				(width 0.15)
				(type solid)
			)
			(fill no)
			(layer "F.Fab")
		)
		(pad "1" smd roundrect
			(at -0.48 0)
			(size 0.59 0.64)
			(layers "F.Cu" "F.Mask" "F.Paste")
			(roundrect_rratio 0.25)
			(net 10 "/DC-DC Converters/VDD_12V_DCDC")
			(pintype "passive")
		)
		(pad "2" smd roundrect
			(at 0.48 0)
			(size 0.59 0.64)
			(layers "F.Cu" "F.Mask" "F.Paste")
			(roundrect_rratio 0.25)
			(net 44 "/DC-DC Converters/12V_ILIM")
			(pintype "passive")
		)
	)
	(footprint "antmicro-footprints:C_0402_1005Metric"
		(layer "F.Cu")
		(at 95.7 88.4 180)
		(descr "Capacitor SMD 0402")
		(tags "capacitor SMD 0402")
		(property "Reference" "C2"
			(at 1.7 -0.6 180)
			(layer "F.SilkS")
			(effects
				(font
					(size 0.7 0.7)
					(thickness 0.15)
				)
				(justify right bottom)
			)
		)
		(property "Value" "C_4u7_25V_0402"
			(at -1.022927 2.155213 0)
			(layer "F.Fab")
			(effects
				(font
					(size 0.7 0.7)
					(thickness 0.15)
				)
				(justify right bottom)
			)
		)
		(property "Datasheet" "https://www.murata.com/products/productdetail?partno=GRM155C61E475ME15%23"
			(at 0 0 180)
			(layer "F.Fab")
			(hide yes)
			(effects
				(font
					(size 1.27 1.27)
					(thickness 0.15)
				)
			)
		)
		(property "Description" "SMD Multilayer Ceramic Capacitor"
			(at 0 0 180)
			(layer "F.Fab")
			(hide yes)
			(effects
				(font
					(size 1.27 1.27)
					(thickness 0.15)
				)
			)
		)
		(property "MPN" "GRM155C61E475ME15J"
			(at 0 0 180)
			(unlocked yes)
			(layer "F.Fab")
			(hide yes)
			(effects
				(font
					(size 1 1)
					(thickness 0.15)
				)
			)
		)
		(property "Manufacturer" "Murata"
			(at 0 0 180)
			(unlocked yes)
			(layer "F.Fab")
			(hide yes)
			(effects
				(font
					(size 1 1)
					(thickness 0.15)
				)
			)
		)
		(property "License" "Apache-2.0"
			(at 0 0 180)
			(unlocked yes)
			(layer "F.Fab")
			(hide yes)
			(effects
				(font
					(size 1 1)
					(thickness 0.15)
				)
			)
		)
		(property "Author" "Antmicro"
			(at 0 0 180)
			(unlocked yes)
			(layer "F.Fab")
			(hide yes)
			(effects
				(font
					(size 1 1)
					(thickness 0.15)
				)
			)
		)
		(property "Val" "4u7"
			(at 0 0 180)
			(unlocked yes)
			(layer "F.Fab")
			(hide yes)
			(effects
				(font
					(size 1 1)
					(thickness 0.15)
				)
			)
		)
		(property "Voltage" "25V"
			(at 0 0 180)
			(unlocked yes)
			(layer "F.Fab")
			(hide yes)
			(effects
				(font
					(size 1 1)
					(thickness 0.15)
				)
			)
		)
		(property "Dielectric" "X5S"
			(at 0 0 180)
			(unlocked yes)
			(layer "F.Fab")
			(hide yes)
			(effects
				(font
					(size 1 1)
					(thickness 0.15)
				)
			)
		)
		(sheetname "/DC-DC Converters/")
		(sheetfile "dc-dc_converters.kicad_sch")
		(attr smd)
		(fp_rect
			(start -0.925 -0.47)
			(end 0.925 0.47)
			(stroke
				(width 0.05)
				(type default)
			)
			(fill no)
			(layer "F.CrtYd")
		)
		(fp_line
			(start 0.504 0.248)
			(end -0.494 0.248)
			(stroke
				(width 0.15)
				(type solid)
			)
			(layer "F.Fab")
		)
		(fp_line
			(start 0.504 -0.25)
			(end 0.504 0.248)
			(stroke
				(width 0.15)
				(type solid)
			)
			(layer "F.Fab")
		)
		(fp_line
			(start -0.494 0.248)
			(end -0.494 -0.25)
			(stroke
				(width 0.15)
				(type solid)
			)
			(layer "F.Fab")
		)
		(fp_line
			(start -0.494 -0.25)
			(end 0.504 -0.25)
			(stroke
				(width 0.15)
				(type solid)
			)
			(layer "F.Fab")
		)
		(pad "1" smd roundrect
			(at -0.48 0 180)
			(size 0.59 0.64)
			(layers "F.Cu" "F.Mask" "F.Paste")
			(roundrect_rratio 0.25)
			(net 2 "GND")
			(pintype "passive")
		)
		(pad "2" smd roundrect
			(at 0.48 0 180)
			(size 0.59 0.64)
			(layers "F.Cu" "F.Mask" "F.Paste")
			(roundrect_rratio 0.25)
			(net 11 "/DC-DC Converters/VDRV_12V_DCDC")
			(pintype "passive")
		)
	)
	(footprint "antmicro-footprints:TP_SMD_0.75mm"
		(layer "F.Cu")
		(at 91.151 78.45)
		(property "Reference" "TP3"
			(at -15.9512 -5.0292 0)
			(layer "F.SilkS")
			(hide yes)
			(effects
				(font
					(size 0.7 0.7)
					(thickness 0.15)
				)
				(justify left bottom)
			)
		)
		(property "Value" "TP_0.75mm_SMD"
			(at 0 1.2 0)
			(layer "F.Fab")
			(effects
				(font
					(size 0.7 0.7)
					(thickness 0.15)
				)
				(justify left bottom)
			)
		)
		(property "Description" "SMT test point"
			(at 0 0 0)
			(layer "F.Fab")
			(hide yes)
			(effects
				(font
					(size 1.27 1.27)
					(thickness 0.15)
				)
			)
		)
		(property "MPN" ""
			(at 0 0 0)
			(unlocked yes)
			(layer "F.Fab")
			(hide yes)
			(effects
				(font
					(size 1 1)
					(thickness 0.15)
				)
			)
		)
		(property "Manufacturer" ""
			(at 0 0 0)
			(unlocked yes)
			(layer "F.Fab")
			(hide yes)
			(effects
				(font
					(size 1 1)
					(thickness 0.15)
				)
			)
		)
		(property "Author" "Antmicro"
			(at 0 0 0)
			(unlocked yes)
			(layer "F.Fab")
			(hide yes)
			(effects
				(font
					(size 1 1)
					(thickness 0.15)
				)
			)
		)
		(property "License" "Apache-2.0"
			(at 0 0 0)
			(unlocked yes)
			(layer "F.Fab")
			(hide yes)
			(effects
				(font
					(size 1 1)
					(thickness 0.15)
				)
			)
		)
		(sheetname "/USB PD/")
		(sheetfile "usb_pd.kicad_sch")
		(attr exclude_from_bom)
		(fp_circle
			(center 0 0)
			(end 0.475 0)
			(stroke
				(width 0.05)
				(type default)
			)
			(fill no)
			(layer "F.CrtYd")
		)
		(pad "1" smd circle
			(at 0 0)
			(size 0.75 0.75)
			(layers "F.Cu" "F.Mask")
			(net 6 "VBUS")
			(pinfunction "1")
			(pintype "passive")
		)
	)
	(footprint "antmicro-footprints:FB_1206_3216Metric"
		(layer "F.Cu")
		(at 83 83.05 -90)
		(property "Reference" "FB2"
			(at 3.2 1.044 0)
			(layer "F.SilkS")
			(effects
				(font
					(size 0.7 0.7)
					(thickness 0.15)
				)
				(justify left bottom)
			)
		)
		(property "Value" "FB_10Z_10A_WE-MPSB_1206"
			(at 0 2 90)
			(layer "F.Fab")
			(effects
				(font
					(size 0.7 0.7)
					(thickness 0.15)
				)
				(justify right bottom)
			)
		)
		(property "Datasheet" "https://www.we-online.com/catalog/datasheet/74279221100.pdf"
			(at 0 0 270)
			(layer "F.Fab")
			(hide yes)
			(effects
				(font
					(size 1.27 1.27)
					(thickness 0.15)
				)
			)
		)
		(property "Description" "Ferrite Bead, 1206 [3216 Metric], 10 ohm, 10.5 A, WE-MPSB, 0.003 ohm, ± 25%, High Current"
			(at 0 0 270)
			(layer "F.Fab")
			(hide yes)
			(effects
				(font
					(size 1.27 1.27)
					(thickness 0.15)
				)
			)
		)
		(property "Val" "10Z/10A"
			(at 0 0 270)
			(unlocked yes)
			(layer "F.Fab")
			(hide yes)
			(effects
				(font
					(size 1 1)
					(thickness 0.15)
				)
			)
		)
		(property "MPN" "74279221100"
			(at 0 0 270)
			(unlocked yes)
			(layer "F.Fab")
			(hide yes)
			(effects
				(font
					(size 1 1)
					(thickness 0.15)
				)
			)
		)
		(property "Manufacturer" "Würth Elektronik"
			(at 0 0 270)
			(unlocked yes)
			(layer "F.Fab")
			(hide yes)
			(effects
				(font
					(size 1 1)
					(thickness 0.15)
				)
			)
		)
		(property "Current" ""
			(at 0 0 270)
			(unlocked yes)
			(layer "F.Fab")
			(hide yes)
			(effects
				(font
					(size 1 1)
					(thickness 0.15)
				)
			)
		)
		(property "Author" "Antmicro"
			(at 0 0 270)
			(unlocked yes)
			(layer "F.Fab")
			(hide yes)
			(effects
				(font
					(size 1 1)
					(thickness 0.15)
				)
			)
		)
		(property "License" "Apache-2.0"
			(at 0 0 270)
			(unlocked yes)
			(layer "F.Fab")
			(hide yes)
			(effects
				(font
					(size 1 1)
					(thickness 0.15)
				)
			)
		)
		(sheetname "/DC-DC Converters/")
		(sheetfile "dc-dc_converters.kicad_sch")
		(attr smd exclude_from_pos_files exclude_from_bom dnp)
		(fp_line
			(start 0.8 0.901)
			(end -0.8 0.901)
			(stroke
				(width 0.15)
				(type solid)
			)
			(layer "F.SilkS")
		)
		(fp_line
			(start 0.8 -0.899)
			(end -0.8 -0.899)
			(stroke
				(width 0.15)
				(type solid)
			)
			(layer "F.SilkS")
		)
		(fp_rect
			(start -2.325 -1.15)
			(end 2.325 1.15)
			(stroke
				(width 0.05)
				(type default)
			)
			(fill no)
			(layer "F.CrtYd")
		)
		(fp_line
			(start -1.677 0.792)
			(end -1.677 -0.861)
			(stroke
				(width 0.15)
				(type solid)
			)
			(layer "F.Fab")
		)
		(fp_line
			(start 1.624 0.792)
			(end -1.677 0.792)
			(stroke
				(width 0.15)
				(type solid)
			)
			(layer "F.Fab")
		)
		(fp_line
			(start -1.677 -0.861)
			(end 1.624 -0.861)
			(stroke
				(width 0.15)
				(type solid)
			)
			(layer "F.Fab")
		)
		(fp_line
			(start 1.624 -0.861)
			(end 1.624 0.792)
			(stroke
				(width 0.15)
				(type solid)
			)
			(layer "F.Fab")
		)
		(pad "1" smd roundrect
			(at -1.5 0.001 270)
			(size 1.15 1.8)
			(layers "F.Cu" "F.Mask" "F.Paste")
			(roundrect_rratio 0.25)
			(net 3 "VCC")
			(pintype "passive")
		)
		(pad "2" smd roundrect
			(at 1.5 0.001 270)
			(size 1.15 1.8)
			(layers "F.Cu" "F.Mask" "F.Paste")
			(roundrect_rratio 0.25)
			(net 5 "+12V")
			(pintype "passive")
		)
	)
	(footprint "antmicro-footprints:R_0402_1005Metric"
		(layer "F.Cu")
		(at 93.799 80.3 -90)
		(descr "Resistor SMD 0402")
		(tags "resistor SMD 0402")
		(property "Reference" "R14"
			(at -0.1 -9.027 180)
			(layer "B.SilkS")
			(effects
				(font
					(size 0.7 0.7)
					(thickness 0.15)
				)
				(justify left bottom mirror)
			)
		)
		(property "Value" "R_3R3_0402"
			(at -1.011843 1.772047 90)
			(layer "F.Fab")
			(effects
				(font
					(size 0.7 0.7)
					(thickness 0.15)
				)
				(justify right bottom)
			)
		)
		(property "Datasheet" "https://www.bourns.com/docs/product-datasheets/cr.pdf"
			(at 0 0 270)
			(layer "F.Fab")
			(hide yes)
			(effects
				(font
					(size 1.27 1.27)
					(thickness 0.15)
				)
			)
		)
		(property "Description" "SMD Chip Resistor, 3.3 ohm, ± 1%, 62.5 mW, 0402 [1005 Metric], Thick Film, General Purpose"
			(at 0 0 270)
			(layer "F.Fab")
			(hide yes)
			(effects
				(font
					(size 1.27 1.27)
					(thickness 0.15)
				)
			)
		)
		(property "Manufacturer" "Bourns"
			(at 0 0 270)
			(unlocked yes)
			(layer "F.Fab")
			(hide yes)
			(effects
				(font
					(size 1 1)
					(thickness 0.15)
				)
			)
		)
		(property "MPN" "CR0402-FX-3R30GLF"
			(at 0 0 270)
			(unlocked yes)
			(layer "F.Fab")
			(hide yes)
			(effects
				(font
					(size 1 1)
					(thickness 0.15)
				)
			)
		)
		(property "Val" "3R3"
			(at 0 0 270)
			(unlocked yes)
			(layer "F.Fab")
			(hide yes)
			(effects
				(font
					(size 1 1)
					(thickness 0.15)
				)
			)
		)
		(property "License" "Apache-2.0"
			(at 0 0 270)
			(unlocked yes)
			(layer "F.Fab")
			(hide yes)
			(effects
				(font
					(size 1 1)
					(thickness 0.15)
				)
			)
		)
		(property "Author" "Antmicro"
			(at 0 0 270)
			(unlocked yes)
			(layer "F.Fab")
			(hide yes)
			(effects
				(font
					(size 1 1)
					(thickness 0.15)
				)
			)
		)
		(property "Tolerance" "1%"
			(at 0 0 270)
			(unlocked yes)
			(layer "F.Fab")
			(hide yes)
			(effects
				(font
					(size 1 1)
					(thickness 0.15)
				)
			)
		)
		(sheetname "/DC-DC Converters/")
		(sheetfile "dc-dc_converters.kicad_sch")
		(attr smd)
		(fp_rect
			(start -0.925 -0.47)
			(end 0.925 0.47)
			(stroke
				(width 0.05)
				(type default)
			)
			(fill no)
			(layer "F.CrtYd")
		)
		(fp_rect
			(start -0.5 -0.25)
			(end 0.5 0.25)
			(stroke
				(width 0.15)
				(type solid)
			)
			(fill no)
			(layer "F.Fab")
		)
		(pad "1" smd roundrect
			(at -0.48 0 270)
			(size 0.59 0.64)
			(layers "F.Cu" "F.Mask" "F.Paste")
			(roundrect_rratio 0.25)
			(net 16 "Net-(C10-Pad1)")
			(pintype "passive")
		)
		(pad "2" smd roundrect
			(at 0.48 0 270)
			(size 0.59 0.64)
			(layers "F.Cu" "F.Mask" "F.Paste")
			(roundrect_rratio 0.25)
			(net 49 "Net-(R14-Pad2)")
			(pintype "passive")
		)
	)
)
